(kicad_pcb
	(version 20260206)
	(generator "pcbnew")
	(generator_version "10.0")
	(general
		(thickness 1.6)
		(legacy_teardrops no)
	)
	(paper "A4")
	(title_block
		(title "04192023_DAF0TMB3IC0_F0TG_MB_C_brd_V02_OCP.brd")
		(comment 1 "Grand Teton / footprints 7251-7257 of 8354")
	)
	(layers
		(0 "F.Cu" signal "TOP")
		(4 "In1.Cu" signal "GND")
		(6 "In2.Cu" signal "IN1")
		(8 "In3.Cu" signal "GND1")
		(10 "In4.Cu" signal "IN2")
		(12 "In5.Cu" signal "GND2")
		(14 "In6.Cu" signal "IN3")
		(16 "In7.Cu" signal "GND3")
		(18 "In8.Cu" signal "VCC")
		(20 "In9.Cu" signal "VCC1")
		(22 "In10.Cu" signal "GND4")
		(24 "In11.Cu" signal "IN4")
		(26 "In12.Cu" signal "GND5")
		(28 "In13.Cu" signal "IN5")
		(30 "In14.Cu" signal "GND6")
		(32 "In15.Cu" signal "IN6")
		(34 "In16.Cu" signal "GND7")
		(2 "B.Cu" signal "BOTTOM")
		(9 "F.Adhes" user "F.Adhesive")
		(11 "B.Adhes" user "B.Adhesive")
		(13 "F.Paste" user "Package Geometry/Pastemask Top")
		(15 "B.Paste" user "Package Geometry/Pastemask Bottom")
		(5 "F.SilkS" user "Ref Des/Silkscreen Top")
		(7 "B.SilkS" user "Ref Des/Silkscreen Bottom")
		(1 "F.Mask" user "Board Geometry/Soldermask Top")
		(3 "B.Mask" user "Board Geometry/Soldermask Bottom")
		(17 "Dwgs.User" user "User.Drawings")
		(19 "Cmts.User" user "User.Comments")
		(21 "Eco1.User" user "User.Eco1")
		(23 "Eco2.User" user "User.Eco2")
		(25 "Edge.Cuts" user "Board Geometry/Outline")
		(27 "Margin" user)
		(31 "F.CrtYd" user "Package Geometry/Place Bound Top")
		(29 "B.CrtYd" user "Package Geometry/Place Bound Bottom")
		(35 "F.Fab" user "Ref Des/Assembly Top")
		(33 "B.Fab" user "Ref Des/Assembly Bottom")
	)
	(footprint ""
		(layer "B.Cu")
		(at 369.884706 -263.46531)
		(property "Reference" "C2647"
			(at 0 0 0)
			(layer "B.SilkS")
			(hide yes)
			(effects
				(font
					(size 1.27 1.27)
				)
				(justify mirror)
			)
		)
		(property "Value" ""
			(at 0 0 0)
			(layer "B.Fab")
			(effects
				(font
					(size 1.27 1.27)
				)
				(justify mirror)
			)
		)
		(duplicate_pad_numbers_are_jumpers no)
		(fp_line
			(start -0.7874 -0.4064)
			(end -0.7874 0.4064)
			(stroke
				(width 0.1524)
				(type default)
			)
			(layer "B.SilkS")
		)
		(fp_line
			(start -0.7874 0.4064)
			(end 0.7874 0.4064)
			(stroke
				(width 0.1524)
				(type default)
			)
			(layer "B.SilkS")
		)
		(fp_line
			(start 0.7874 -0.4064)
			(end -0.7874 -0.4064)
			(stroke
				(width 0.1524)
				(type default)
			)
			(layer "B.SilkS")
		)
		(fp_line
			(start 0.7874 0.4064)
			(end 0.7874 -0.4064)
			(stroke
				(width 0.1524)
				(type default)
			)
			(layer "B.SilkS")
		)
		(fp_line
			(start -0.67945 -0.3048)
			(end -0.67945 0.3048)
			(stroke
				(width 0.1)
				(type default)
			)
			(layer "B.Fab")
		)
		(fp_line
			(start -0.67945 0.3048)
			(end -0.120396 0.3048)
			(stroke
				(width 0.1)
				(type default)
			)
			(layer "B.Fab")
		)
		(fp_line
			(start -0.12065 -0.3048)
			(end -0.67945 -0.3048)
			(stroke
				(width 0.1)
				(type default)
			)
			(layer "B.Fab")
		)
		(fp_line
			(start -0.12065 -0.2794)
			(end -0.12065 -0.3048)
			(stroke
				(width 0.1)
				(type default)
			)
			(layer "B.Fab")
		)
		(fp_line
			(start -0.120396 0.2794)
			(end 0.12065 0.2794)
			(stroke
				(width 0.1)
				(type default)
			)
			(layer "B.Fab")
		)
		(fp_line
			(start -0.120396 0.3048)
			(end -0.120396 0.2794)
			(stroke
				(width 0.1)
				(type default)
			)
			(layer "B.Fab")
		)
		(fp_line
			(start 0.12065 -0.305054)
			(end 0.12065 -0.2794)
			(stroke
				(width 0.1)
				(type default)
			)
			(layer "B.Fab")
		)
		(fp_line
			(start 0.12065 -0.2794)
			(end -0.12065 -0.2794)
			(stroke
				(width 0.1)
				(type default)
			)
			(layer "B.Fab")
		)
		(fp_line
			(start 0.12065 0.2794)
			(end 0.12065 0.3048)
			(stroke
				(width 0.1)
				(type default)
			)
			(layer "B.Fab")
		)
		(fp_line
			(start 0.12065 0.3048)
			(end 0.67945 0.3048)
			(stroke
				(width 0.1)
				(type default)
			)
			(layer "B.Fab")
		)
		(fp_line
			(start 0.67945 -0.305054)
			(end 0.12065 -0.305054)
			(stroke
				(width 0.1)
				(type default)
			)
			(layer "B.Fab")
		)
		(fp_line
			(start 0.67945 0.3048)
			(end 0.67945 -0.305054)
			(stroke
				(width 0.1)
				(type default)
			)
			(layer "B.Fab")
		)
		(pad "1" smd circle
			(at 0.40005 0 180)
			(size 0 0)
			(layers "B.Cu" "B.Mask" "B.Paste")
			(net "PVDD11_S3_P0")
		)
		(pad "2" smd circle
			(at -0.40005 0 180)
			(size 0 0)
			(layers "B.Cu" "B.Mask" "B.Paste")
			(net "GND")
		)
	)
	(footprint ""
		(layer "B.Cu")
		(at 320.846958 -197.567296)
		(property "Reference" "R409"
			(at 0 0 0)
			(layer "B.SilkS")
			(hide yes)
			(effects
				(font
					(size 1.27 1.27)
				)
				(justify mirror)
			)
		)
		(property "Value" ""
			(at 0 0 0)
			(layer "B.Fab")
			(effects
				(font
					(size 1.27 1.27)
				)
				(justify mirror)
			)
		)
		(duplicate_pad_numbers_are_jumpers no)
		(fp_line
			(start -0.7874 -0.4064)
			(end -0.7874 0.4064)
			(stroke
				(width 0.1524)
				(type default)
			)
			(layer "B.SilkS")
		)
		(fp_line
			(start -0.7874 0.4064)
			(end 0.7874 0.4064)
			(stroke
				(width 0.1524)
				(type default)
			)
			(layer "B.SilkS")
		)
		(fp_line
			(start 0.7874 -0.4064)
			(end -0.7874 -0.4064)
			(stroke
				(width 0.1524)
				(type default)
			)
			(layer "B.SilkS")
		)
		(fp_line
			(start 0.7874 0.4064)
			(end 0.7874 -0.4064)
			(stroke
				(width 0.1524)
				(type default)
			)
			(layer "B.SilkS")
		)
		(fp_line
			(start -0.67945 -0.3048)
			(end -0.67945 0.3048)
			(stroke
				(width 0.1)
				(type default)
			)
			(layer "B.Fab")
		)
		(fp_line
			(start -0.67945 0.3048)
			(end -0.120396 0.3048)
			(stroke
				(width 0.1)
				(type default)
			)
			(layer "B.Fab")
		)
		(fp_line
			(start -0.12065 -0.3048)
			(end -0.67945 -0.3048)
			(stroke
				(width 0.1)
				(type default)
			)
			(layer "B.Fab")
		)
		(fp_line
			(start -0.12065 -0.2794)
			(end -0.12065 -0.3048)
			(stroke
				(width 0.1)
				(type default)
			)
			(layer "B.Fab")
		)
		(fp_line
			(start -0.120396 0.2794)
			(end 0.12065 0.2794)
			(stroke
				(width 0.1)
				(type default)
			)
			(layer "B.Fab")
		)
		(fp_line
			(start -0.120396 0.3048)
			(end -0.120396 0.2794)
			(stroke
				(width 0.1)
				(type default)
			)
			(layer "B.Fab")
		)
		(fp_line
			(start 0.12065 -0.305054)
			(end 0.12065 -0.2794)
			(stroke
				(width 0.1)
				(type default)
			)
			(layer "B.Fab")
		)
		(fp_line
			(start 0.12065 -0.2794)
			(end -0.12065 -0.2794)
			(stroke
				(width 0.1)
				(type default)
			)
			(layer "B.Fab")
		)
		(fp_line
			(start 0.12065 0.2794)
			(end 0.12065 0.3048)
			(stroke
				(width 0.1)
				(type default)
			)
			(layer "B.Fab")
		)
		(fp_line
			(start 0.12065 0.3048)
			(end 0.67945 0.3048)
			(stroke
				(width 0.1)
				(type default)
			)
			(layer "B.Fab")
		)
		(fp_line
			(start 0.67945 -0.305054)
			(end 0.12065 -0.305054)
			(stroke
				(width 0.1)
				(type default)
			)
			(layer "B.Fab")
		)
		(fp_line
			(start 0.67945 0.3048)
			(end 0.67945 -0.305054)
			(stroke
				(width 0.1)
				(type default)
			)
			(layer "B.Fab")
		)
		(pad "1" smd circle
			(at 0.40005 0 180)
			(size 0 0)
			(layers "B.Cu" "B.Mask" "B.Paste")
			(net "CPU0_BP1")
		)
		(pad "2" smd circle
			(at -0.40005 0 180)
			(size 0 0)
			(layers "B.Cu" "B.Mask" "B.Paste")
			(net "PVDD18_S5_P0")
		)
	)
	(footprint ""
		(layer "B.Cu")
		(at 145.331434 -203.679552 90)
		(property "Reference" "R522"
			(at 0 0 90)
			(layer "B.SilkS")
			(hide yes)
			(effects
				(font
					(size 1.27 1.27)
				)
				(justify mirror)
			)
		)
		(property "Value" ""
			(at 0 0 90)
			(layer "B.Fab")
			(effects
				(font
					(size 1.27 1.27)
				)
				(justify mirror)
			)
		)
		(duplicate_pad_numbers_are_jumpers no)
		(fp_line
			(start 0.7874 -0.4064)
			(end -0.7874 -0.4064)
			(stroke
				(width 0.1524)
				(type default)
			)
			(layer "B.SilkS")
		)
		(fp_line
			(start -0.7874 -0.4064)
			(end -0.7874 0.4064)
			(stroke
				(width 0.1524)
				(type default)
			)
			(layer "B.SilkS")
		)
		(fp_line
			(start 0.7874 0.4064)
			(end 0.7874 -0.4064)
			(stroke
				(width 0.1524)
				(type default)
			)
			(layer "B.SilkS")
		)
		(fp_line
			(start -0.7874 0.4064)
			(end 0.7874 0.4064)
			(stroke
				(width 0.1524)
				(type default)
			)
			(layer "B.SilkS")
		)
		(fp_line
			(start 0.67945 -0.305054)
			(end 0.12065 -0.305054)
			(stroke
				(width 0.1)
				(type default)
			)
			(layer "B.Fab")
		)
		(fp_line
			(start 0.12065 -0.305054)
			(end 0.12065 -0.2794)
			(stroke
				(width 0.1)
				(type default)
			)
			(layer "B.Fab")
		)
		(fp_line
			(start -0.12065 -0.3048)
			(end -0.67945 -0.3048)
			(stroke
				(width 0.1)
				(type default)
			)
			(layer "B.Fab")
		)
		(fp_line
			(start -0.67945 -0.3048)
			(end -0.67945 0.3048)
			(stroke
				(width 0.1)
				(type default)
			)
			(layer "B.Fab")
		)
		(fp_line
			(start 0.12065 -0.2794)
			(end -0.12065 -0.2794)
			(stroke
				(width 0.1)
				(type default)
			)
			(layer "B.Fab")
		)
		(fp_line
			(start -0.12065 -0.2794)
			(end -0.12065 -0.3048)
			(stroke
				(width 0.1)
				(type default)
			)
			(layer "B.Fab")
		)
		(fp_line
			(start 0.12065 0.2794)
			(end 0.12065 0.3048)
			(stroke
				(width 0.1)
				(type default)
			)
			(layer "B.Fab")
		)
		(fp_line
			(start -0.120396 0.2794)
			(end 0.12065 0.2794)
			(stroke
				(width 0.1)
				(type default)
			)
			(layer "B.Fab")
		)
		(fp_line
			(start 0.67945 0.3048)
			(end 0.67945 -0.305054)
			(stroke
				(width 0.1)
				(type default)
			)
			(layer "B.Fab")
		)
		(fp_line
			(start 0.12065 0.3048)
			(end 0.67945 0.3048)
			(stroke
				(width 0.1)
				(type default)
			)
			(layer "B.Fab")
		)
		(fp_line
			(start -0.120396 0.3048)
			(end -0.120396 0.2794)
			(stroke
				(width 0.1)
				(type default)
			)
			(layer "B.Fab")
		)
		(fp_line
			(start -0.67945 0.3048)
			(end -0.120396 0.3048)
			(stroke
				(width 0.1)
				(type default)
			)
			(layer "B.Fab")
		)
		(pad "1" smd circle
			(at 0.40005 0 270)
			(size 0 0)
			(layers "B.Cu" "B.Mask" "B.Paste")
			(net "P3V3_AUX")
		)
		(pad "2" smd circle
			(at -0.40005 0 270)
			(size 0 0)
			(layers "B.Cu" "B.Mask" "B.Paste")
			(net "CPU1_SP5R1")
		)
	)
	(footprint ""
		(layer "B.Cu")
		(at 137.843006 -408.517344 90)
		(property "Reference" "C6740"
			(at 0 0 90)
			(layer "B.SilkS")
			(hide yes)
			(effects
				(font
					(size 1.27 1.27)
				)
				(justify mirror)
			)
		)
		(property "Value" ""
			(at 0 0 90)
			(layer "B.Fab")
			(effects
				(font
					(size 1.27 1.27)
				)
				(justify mirror)
			)
		)
		(duplicate_pad_numbers_are_jumpers no)
		(fp_line
			(start 0.299974 -0.150114)
			(end -0.299974 -0.150114)
			(stroke
				(width 0.1)
				(type default)
			)
			(layer "B.Fab")
		)
		(fp_line
			(start -0.299974 -0.150114)
			(end -0.299974 0.150114)
			(stroke
				(width 0.1)
				(type default)
			)
			(layer "B.Fab")
		)
		(fp_line
			(start 0.299974 0.150114)
			(end 0.299974 -0.150114)
			(stroke
				(width 0.1)
				(type default)
			)
			(layer "B.Fab")
		)
		(fp_line
			(start -0.299974 0.150114)
			(end 0.299974 0.150114)
			(stroke
				(width 0.1)
				(type default)
			)
			(layer "B.Fab")
		)
		(pad "1" smd rect
			(at 0.2667 0 270)
			(size 0.3048 0.381)
			(layers "B.Cu" "B.Mask" "B.Paste")
			(net "P5E_CPU1_P3_TX_BUF_C_DN<7>")
		)
		(pad "2" smd rect
			(at -0.2667 0 270)
			(size 0.3048 0.381)
			(layers "B.Cu" "B.Mask" "B.Paste")
			(net "P5E_CPU1_P3_TX_BUF_DN<7>")
		)
	)
	(footprint ""
		(layer "B.Cu")
		(at 314.191142 -398.942052 90)
		(property "Reference" "C563"
			(at 0 0 90)
			(layer "B.SilkS")
			(hide yes)
			(effects
				(font
					(size 1.27 1.27)
				)
				(justify mirror)
			)
		)
		(property "Value" ""
			(at 0 0 90)
			(layer "B.Fab")
			(effects
				(font
					(size 1.27 1.27)
				)
				(justify mirror)
			)
		)
		(duplicate_pad_numbers_are_jumpers no)
		(fp_line
			(start 0.7874 -0.4064)
			(end -0.7874 -0.4064)
			(stroke
				(width 0.1524)
				(type default)
			)
			(layer "B.SilkS")
		)
		(fp_line
			(start -0.7874 -0.4064)
			(end -0.7874 0.4064)
			(stroke
				(width 0.1524)
				(type default)
			)
			(layer "B.SilkS")
		)
		(fp_line
			(start 0.7874 0.4064)
			(end 0.7874 -0.4064)
			(stroke
				(width 0.1524)
				(type default)
			)
			(layer "B.SilkS")
		)
		(fp_line
			(start -0.7874 0.4064)
			(end 0.7874 0.4064)
			(stroke
				(width 0.1524)
				(type default)
			)
			(layer "B.SilkS")
		)
		(fp_line
			(start 0.67945 -0.305054)
			(end 0.12065 -0.305054)
			(stroke
				(width 0.1)
				(type default)
			)
			(layer "B.Fab")
		)
		(fp_line
			(start 0.12065 -0.305054)
			(end 0.12065 -0.2794)
			(stroke
				(width 0.1)
				(type default)
			)
			(layer "B.Fab")
		)
		(fp_line
			(start -0.12065 -0.3048)
			(end -0.67945 -0.3048)
			(stroke
				(width 0.1)
				(type default)
			)
			(layer "B.Fab")
		)
		(fp_line
			(start -0.67945 -0.3048)
			(end -0.67945 0.3048)
			(stroke
				(width 0.1)
				(type default)
			)
			(layer "B.Fab")
		)
		(fp_line
			(start 0.12065 -0.2794)
			(end -0.12065 -0.2794)
			(stroke
				(width 0.1)
				(type default)
			)
			(layer "B.Fab")
		)
		(fp_line
			(start -0.12065 -0.2794)
			(end -0.12065 -0.3048)
			(stroke
				(width 0.1)
				(type default)
			)
			(layer "B.Fab")
		)
		(fp_line
			(start 0.12065 0.2794)
			(end 0.12065 0.3048)
			(stroke
				(width 0.1)
				(type default)
			)
			(layer "B.Fab")
		)
		(fp_line
			(start -0.120396 0.2794)
			(end 0.12065 0.2794)
			(stroke
				(width 0.1)
				(type default)
			)
			(layer "B.Fab")
		)
		(fp_line
			(start 0.67945 0.3048)
			(end 0.67945 -0.305054)
			(stroke
				(width 0.1)
				(type default)
			)
			(layer "B.Fab")
		)
		(fp_line
			(start 0.12065 0.3048)
			(end 0.67945 0.3048)
			(stroke
				(width 0.1)
				(type default)
			)
			(layer "B.Fab")
		)
		(fp_line
			(start -0.120396 0.3048)
			(end -0.120396 0.2794)
			(stroke
				(width 0.1)
				(type default)
			)
			(layer "B.Fab")
		)
		(fp_line
			(start -0.67945 0.3048)
			(end -0.120396 0.3048)
			(stroke
				(width 0.1)
				(type default)
			)
			(layer "B.Fab")
		)
		(pad "1" smd circle
			(at 0.40005 0 270)
			(size 0 0)
			(layers "B.Cu" "B.Mask" "B.Paste")
			(net "P0V9_CPU0_RT_2D")
		)
		(pad "2" smd circle
			(at -0.40005 0 270)
			(size 0 0)
			(layers "B.Cu" "B.Mask" "B.Paste")
			(net "GND")
		)
	)
	(footprint ""
		(layer "B.Cu")
		(at 173.609 -100.294948 -90)
		(property "Reference" "R6016"
			(at 0 0 90)
			(layer "B.SilkS")
			(hide yes)
			(effects
				(font
					(size 1.27 1.27)
				)
				(justify mirror)
			)
		)
		(property "Value" ""
			(at 0 0 90)
			(layer "B.Fab")
			(effects
				(font
					(size 1.27 1.27)
				)
				(justify mirror)
			)
		)
		(duplicate_pad_numbers_are_jumpers no)
		(fp_line
			(start -0.7874 0.4064)
			(end 0.7874 0.4064)
			(stroke
				(width 0.1524)
				(type default)
			)
			(layer "B.SilkS")
		)
		(fp_line
			(start 0.7874 0.4064)
			(end 0.7874 -0.4064)
			(stroke
				(width 0.1524)
				(type default)
			)
			(layer "B.SilkS")
		)
		(fp_line
			(start -0.7874 -0.4064)
			(end -0.7874 0.4064)
			(stroke
				(width 0.1524)
				(type default)
			)
			(layer "B.SilkS")
		)
		(fp_line
			(start 0.7874 -0.4064)
			(end -0.7874 -0.4064)
			(stroke
				(width 0.1524)
				(type default)
			)
			(layer "B.SilkS")
		)
		(fp_line
			(start -0.67945 0.3048)
			(end -0.120396 0.3048)
			(stroke
				(width 0.1)
				(type default)
			)
			(layer "B.Fab")
		)
		(fp_line
			(start -0.120396 0.3048)
			(end -0.120396 0.2794)
			(stroke
				(width 0.1)
				(type default)
			)
			(layer "B.Fab")
		)
		(fp_line
			(start 0.12065 0.3048)
			(end 0.67945 0.3048)
			(stroke
				(width 0.1)
				(type default)
			)
			(layer "B.Fab")
		)
		(fp_line
			(start 0.67945 0.3048)
			(end 0.67945 -0.305054)
			(stroke
				(width 0.1)
				(type default)
			)
			(layer "B.Fab")
		)
		(fp_line
			(start -0.120396 0.2794)
			(end 0.12065 0.2794)
			(stroke
				(width 0.1)
				(type default)
			)
			(layer "B.Fab")
		)
		(fp_line
			(start 0.12065 0.2794)
			(end 0.12065 0.3048)
			(stroke
				(width 0.1)
				(type default)
			)
			(layer "B.Fab")
		)
		(fp_line
			(start -0.12065 -0.2794)
			(end -0.12065 -0.3048)
			(stroke
				(width 0.1)
				(type default)
			)
			(layer "B.Fab")
		)
		(fp_line
			(start 0.12065 -0.2794)
			(end -0.12065 -0.2794)
			(stroke
				(width 0.1)
				(type default)
			)
			(layer "B.Fab")
		)
		(fp_line
			(start -0.67945 -0.3048)
			(end -0.67945 0.3048)
			(stroke
				(width 0.1)
				(type default)
			)
			(layer "B.Fab")
		)
		(fp_line
			(start -0.12065 -0.3048)
			(end -0.67945 -0.3048)
			(stroke
				(width 0.1)
				(type default)
			)
			(layer "B.Fab")
		)
		(fp_line
			(start 0.12065 -0.305054)
			(end 0.12065 -0.2794)
			(stroke
				(width 0.1)
				(type default)
			)
			(layer "B.Fab")
		)
		(fp_line
			(start 0.67945 -0.305054)
			(end 0.12065 -0.305054)
			(stroke
				(width 0.1)
				(type default)
			)
			(layer "B.Fab")
		)
		(pad "1" smd circle
			(at 0.40005 0 90)
			(size 0 0)
			(layers "B.Cu" "B.Mask" "B.Paste")
			(net "P3V3_AUX")
		)
		(pad "2" smd circle
			(at -0.40005 0 90)
			(size 0 0)
			(layers "B.Cu" "B.Mask" "B.Paste")
			(net "SGPIO_SCM_DO_<0>")
		)
	)
	(footprint ""
		(layer "B.Cu")
		(at 188.710824 -136.658096 90)
		(property "Reference" "R194"
			(at 0 0 90)
			(layer "B.SilkS")
			(hide yes)
			(effects
				(font
					(size 1.27 1.27)
				)
				(justify mirror)
			)
		)
		(property "Value" ""
			(at 0 0 90)
			(layer "B.Fab")
			(effects
				(font
					(size 1.27 1.27)
				)
				(justify mirror)
			)
		)
		(duplicate_pad_numbers_are_jumpers no)
		(fp_line
			(start 0.7874 -0.4064)
			(end -0.7874 -0.4064)
			(stroke
				(width 0.1524)
				(type default)
			)
			(layer "B.SilkS")
		)
		(fp_line
			(start -0.7874 -0.4064)
			(end -0.7874 0.4064)
			(stroke
				(width 0.1524)
				(type default)
			)
			(layer "B.SilkS")
		)
		(fp_line
			(start 0.7874 0.4064)
			(end 0.7874 -0.4064)
			(stroke
				(width 0.1524)
				(type default)
			)
			(layer "B.SilkS")
		)
		(fp_line
			(start -0.7874 0.4064)
			(end 0.7874 0.4064)
			(stroke
				(width 0.1524)
				(type default)
			)
			(layer "B.SilkS")
		)
		(fp_line
			(start 0.67945 -0.305054)
			(end 0.12065 -0.305054)
			(stroke
				(width 0.1)
				(type default)
			)
			(layer "B.Fab")
		)
		(fp_line
			(start 0.12065 -0.305054)
			(end 0.12065 -0.2794)
			(stroke
				(width 0.1)
				(type default)
			)
			(layer "B.Fab")
		)
		(fp_line
			(start -0.12065 -0.3048)
			(end -0.67945 -0.3048)
			(stroke
				(width 0.1)
				(type default)
			)
			(layer "B.Fab")
		)
		(fp_line
			(start -0.67945 -0.3048)
			(end -0.67945 0.3048)
			(stroke
				(width 0.1)
				(type default)
			)
			(layer "B.Fab")
		)
		(fp_line
			(start 0.12065 -0.2794)
			(end -0.12065 -0.2794)
			(stroke
				(width 0.1)
				(type default)
			)
			(layer "B.Fab")
		)
		(fp_line
			(start -0.12065 -0.2794)
			(end -0.12065 -0.3048)
			(stroke
				(width 0.1)
				(type default)
			)
			(layer "B.Fab")
		)
		(fp_line
			(start 0.12065 0.2794)
			(end 0.12065 0.3048)
			(stroke
				(width 0.1)
				(type default)
			)
			(layer "B.Fab")
		)
		(fp_line
			(start -0.120396 0.2794)
			(end 0.12065 0.2794)
			(stroke
				(width 0.1)
				(type default)
			)
			(layer "B.Fab")
		)
		(fp_line
			(start 0.67945 0.3048)
			(end 0.67945 -0.305054)
			(stroke
				(width 0.1)
				(type default)
			)
			(layer "B.Fab")
		)
		(fp_line
			(start 0.12065 0.3048)
			(end 0.67945 0.3048)
			(stroke
				(width 0.1)
				(type default)
			)
			(layer "B.Fab")
		)
		(fp_line
			(start -0.120396 0.3048)
			(end -0.120396 0.2794)
			(stroke
				(width 0.1)
				(type default)
			)
			(layer "B.Fab")
		)
		(fp_line
			(start -0.67945 0.3048)
			(end -0.120396 0.3048)
			(stroke
				(width 0.1)
				(type default)
			)
			(layer "B.Fab")
		)
		(pad "1" smd circle
			(at 0.40005 0 270)
			(size 0 0)
			(layers "B.Cu" "B.Mask" "B.Paste")
			(net "CPU1_SPD_HOST_CTRL_N")
		)
		(pad "2" smd circle
			(at -0.40005 0 270)
			(size 0 0)
			(layers "B.Cu" "B.Mask" "B.Paste")
			(net "CPU1_SPD_HOST_CTRL_R1_N")
		)
	)
)
